FILE_TYPE = MULTI_PHYS_TABLE;

PART '2N7002A7'

{========================================================================================}
:VALUE       | PART_TYPE | MATERIAL | PART_NUMBER    = STANDARD | LIFECYCLE      | PART_NUMBER   | JEDEC_TYPE    | DESCRIPTION                             | MANUFTR | MANUF_PN    | RD_CMPLS_LVL | CMPLS_LVL | CLASS | DIP_SMD | FP_ECN | FROM_PJ    | DATA          | EE_CHECK_LIST | STATUS | PSL | PREFERENCE | CREATOR | CREATEDAY  ;
{========================================================================================}
 '2N7002A-7' | 'SMLF'    | 'IC'     | 'BAM70020068'(!) = ''       | ''               | 'BAM70020068' |'SOT23_GDSXC'| 'TRANS MOS 2N7002A-7(60V,0.115A,0.25W)' | 'DDS'   | '2N7002A-7' | 'EP(V1)'     | ''        | 'IC'  | ''      | ''     | 'S1A-TONY' | '2N7002A.pdf' | ''            | ''     | ''  | ''         | ''      | '20140318'
 '2N7002A-7' | 'SMLF'    | 'EMPTY'  | 'BAM70020068'(!) = ''       | ''               | 'BAM70020068' |'SOT23_GDSXC'| 'TRANS MOS 2N7002A-7(60V,0.115A,0.25W)' | 'DDS'   | '2N7002A-7' | 'EP(V1)'     | ''        | 'IC'  | ''      | ''     | 'S1A-TONY' | '2N7002A.pdf' | ''            | ''     | ''  | ''         | ''      | '20140318'

END_PART

END.

